# S9S_MB_2U (Grand Teton) — schematic netlist excerpt (pin names and nets, part order shuffled) for the footprints in the layout excerpt that follows; sources: Cadence DE-HDL packaged netlist, KiCad conversion of 03242023_DA0F0TMBIJ0_F0T_Motherboard_J_brd_V01_OCP.brd

Q142  BC847BPN  IC  pkg SOT363XB  page 122
  E1  = GND
  B1  = H_CPU1_MEMHOT_OUT_R
  C2  = H_CPU1_MEMHOT_OUT
  E2  = PVNN_TERM_CPU1
  B2  = H_CPU1_MEMHOT_OUT_VT_R_N
  C1  = H_CPU1_MEMHOT_OUT_VT_N

R3591  Q_RES  33.2 1% CHIP  pkg 0402LF  page 232 : A = SMB_INA230_3V3AUX_SDA ; B = SMB_INA230_3_3V3AUX_SDA_R
C707  Q_CAP_DIFFBUS  DIFF BUS_0.22UF 6.3V 20% X6S  pkg C0201  page 177 : \1\ = P5E_CPU1_PE4_TX_C_DP<1> ; \2\ = P5E_CPU1_PE4_TX_DP<1>

(kicad_pcb
	(version 20260206)
	(generator "pcbnew")
	(generator_version "10.0")
	(general
		(thickness 1.6)
		(legacy_teardrops no)
	)
	(paper "A4")
	(title_block
		(title "03242023_DA0F0TMBIJ0_F0T_Motherboard_J_brd_V01_OCP.brd")
		(comment 1 "Grand Teton / footprints 2418-2420 of 6105")
	)
	(layers
		(0 "F.Cu" signal "TOP")
		(4 "In1.Cu" signal "GND")
		(6 "In2.Cu" signal "IN1")
		(8 "In3.Cu" signal "GND1")
		(10 "In4.Cu" signal "IN2")
		(12 "In5.Cu" signal "GND2")
		(14 "In6.Cu" signal "IN3")
		(16 "In7.Cu" signal "GND3")
		(18 "In8.Cu" signal "VCC")
		(20 "In9.Cu" signal "VCC1")
		(22 "In10.Cu" signal "GND4")
		(24 "In11.Cu" signal "IN4")
		(26 "In12.Cu" signal "GND5")
		(28 "In13.Cu" signal "IN5")
		(30 "In14.Cu" signal "GND6")
		(32 "In15.Cu" signal "IN6")
		(34 "In16.Cu" signal "GND7")
		(2 "B.Cu" signal "BOTTOM")
		(9 "F.Adhes" user "F.Adhesive")
		(11 "B.Adhes" user "B.Adhesive")
		(13 "F.Paste" user "Package Geometry/Pastemask Top")
		(15 "B.Paste" user "Package Geometry/Pastemask Bottom")
		(5 "F.SilkS" user "Ref Des/Silkscreen Top")
		(7 "B.SilkS" user "Ref Des/Silkscreen Bottom")
		(1 "F.Mask" user "Board Geometry/Soldermask Top")
		(3 "B.Mask" user "Board Geometry/Soldermask Bottom")
		(17 "Dwgs.User" user "User.Drawings")
		(19 "Cmts.User" user "User.Comments")
		(21 "Eco1.User" user "User.Eco1")
		(23 "Eco2.User" user "User.Eco2")
		(25 "Edge.Cuts" user "Board Geometry/Outline")
		(27 "Margin" user)
		(31 "F.CrtYd" user "Package Geometry/Place Bound Top")
		(29 "B.CrtYd" user "Package Geometry/Place Bound Bottom")
		(35 "F.Fab" user "Ref Des/Assembly Top")
		(33 "B.Fab" user "Ref Des/Assembly Bottom")
	)
	(footprint ""
		(layer "F.Cu")
		(at 68.961 -34.788348)
		(property "Reference" "R3591"
			(at 0 0 0)
			(layer "F.SilkS")
			(hide yes)
			(effects
				(font
					(size 1.27 1.27)
				)
			)
		)
		(property "Value" ""
			(at 0 0 0)
			(layer "F.Fab")
			(effects
				(font
					(size 1.27 1.27)
				)
			)
		)
		(duplicate_pad_numbers_are_jumpers no)
		(fp_line
			(start -0.7874 -0.4064)
			(end 0.7874 -0.4064)
			(stroke
				(width 0.1524)
				(type default)
			)
			(layer "F.SilkS")
		)
		(fp_line
			(start -0.7874 0.4064)
			(end -0.7874 -0.4064)
			(stroke
				(width 0.1524)
				(type default)
			)
			(layer "F.SilkS")
		)
		(fp_line
			(start 0.7874 -0.4064)
			(end 0.7874 0.4064)
			(stroke
				(width 0.1524)
				(type default)
			)
			(layer "F.SilkS")
		)
		(fp_line
			(start 0.7874 0.4064)
			(end -0.7874 0.4064)
			(stroke
				(width 0.1524)
				(type default)
			)
			(layer "F.SilkS")
		)
		(fp_line
			(start -0.67945 -0.305054)
			(end -0.12065 -0.305054)
			(stroke
				(width 0.1)
				(type default)
			)
			(layer "F.Fab")
		)
		(fp_line
			(start -0.67945 0.3048)
			(end -0.67945 -0.305054)
			(stroke
				(width 0.1)
				(type default)
			)
			(layer "F.Fab")
		)
		(fp_line
			(start -0.12065 -0.305054)
			(end -0.12065 -0.2794)
			(stroke
				(width 0.1)
				(type default)
			)
			(layer "F.Fab")
		)
		(fp_line
			(start -0.12065 -0.2794)
			(end 0.12065 -0.2794)
			(stroke
				(width 0.1)
				(type default)
			)
			(layer "F.Fab")
		)
		(fp_line
			(start -0.12065 0.2794)
			(end -0.12065 0.3048)
			(stroke
				(width 0.1)
				(type default)
			)
			(layer "F.Fab")
		)
		(fp_line
			(start -0.12065 0.3048)
			(end -0.67945 0.3048)
			(stroke
				(width 0.1)
				(type default)
			)
			(layer "F.Fab")
		)
		(fp_line
			(start 0.120396 0.2794)
			(end -0.12065 0.2794)
			(stroke
				(width 0.1)
				(type default)
			)
			(layer "F.Fab")
		)
		(fp_line
			(start 0.120396 0.3048)
			(end 0.120396 0.2794)
			(stroke
				(width 0.1)
				(type default)
			)
			(layer "F.Fab")
		)
		(fp_line
			(start 0.12065 -0.3048)
			(end 0.67945 -0.3048)
			(stroke
				(width 0.1)
				(type default)
			)
			(layer "F.Fab")
		)
		(fp_line
			(start 0.12065 -0.2794)
			(end 0.12065 -0.3048)
			(stroke
				(width 0.1)
				(type default)
			)
			(layer "F.Fab")
		)
		(fp_line
			(start 0.67945 -0.3048)
			(end 0.67945 0.3048)
			(stroke
				(width 0.1)
				(type default)
			)
			(layer "F.Fab")
		)
		(fp_line
			(start 0.67945 0.3048)
			(end 0.120396 0.3048)
			(stroke
				(width 0.1)
				(type default)
			)
			(layer "F.Fab")
		)
		(pad "1" smd circle
			(at -0.40005 0)
			(size 0 0)
			(layers "F.Cu" "F.Mask" "F.Paste")
			(net "SMB_INA230_3V3AUX_SDA")
		)
		(pad "2" smd circle
			(at 0.40005 0)
			(size 0 0)
			(layers "F.Cu" "F.Mask" "F.Paste")
			(net "SMB_INA230_3_3V3AUX_SDA_R")
		)
	)
	(footprint ""
		(layer "F.Cu")
		(at 52.363878 -408.517344 -90)
		(property "Reference" "C707"
			(at 0 0 270)
			(layer "F.SilkS")
			(hide yes)
			(effects
				(font
					(size 1.27 1.27)
				)
			)
		)
		(property "Value" ""
			(at 0 0 270)
			(layer "F.Fab")
			(effects
				(font
					(size 1.27 1.27)
				)
			)
		)
		(duplicate_pad_numbers_are_jumpers no)
		(fp_line
			(start -0.299974 0.150114)
			(end -0.299974 -0.150114)
			(stroke
				(width 0.1)
				(type default)
			)
			(layer "F.Fab")
		)
		(fp_line
			(start 0.299974 0.150114)
			(end -0.299974 0.150114)
			(stroke
				(width 0.1)
				(type default)
			)
			(layer "F.Fab")
		)
		(fp_line
			(start -0.299974 -0.150114)
			(end 0.299974 -0.150114)
			(stroke
				(width 0.1)
				(type default)
			)
			(layer "F.Fab")
		)
		(fp_line
			(start 0.299974 -0.150114)
			(end 0.299974 0.150114)
			(stroke
				(width 0.1)
				(type default)
			)
			(layer "F.Fab")
		)
		(pad "1" smd rect
			(at -0.2667 0 270)
			(size 0.3048 0.381)
			(layers "F.Cu" "F.Mask" "F.Paste")
			(net "P5E_CPU1_PE4_TX_C_DP<1>")
		)
		(pad "2" smd rect
			(at 0.2667 0 270)
			(size 0.3048 0.381)
			(layers "F.Cu" "F.Mask" "F.Paste")
			(net "P5E_CPU1_PE4_TX_DP<1>")
		)
	)
	(footprint ""
		(layer "F.Cu")
		(at 134.42188 -96.357948 -90)
		(property "Reference" "Q142"
			(at -0.035052 -2.38379 90)
			(unlocked yes)
			(layer "F.SilkS")
			(effects
				(font
					(size 0.7874 0.5842)
					(thickness 0.1524)
				)
			)
		)
		(property "Value" ""
			(at 0 0 270)
			(layer "F.Fab")
			(effects
				(font
					(size 1.27 1.27)
				)
			)
		)
		(duplicate_pad_numbers_are_jumpers no)
		(fp_line
			(start -1.376172 1.199896)
			(end -1.376172 -1.199896)
			(stroke
				(width 0.1524)
				(type default)
			)
			(layer "F.SilkS")
		)
		(fp_line
			(start 1.376172 1.199896)
			(end -1.376172 1.199896)
			(stroke
				(width 0.1524)
				(type default)
			)
			(layer "F.SilkS")
		)
		(fp_line
			(start 0 -0.762)
			(end 0.508 -1.199896)
			(stroke
				(width 0.1524)
				(type default)
			)
			(layer "F.SilkS")
		)
		(fp_line
			(start -1.376172 -1.199896)
			(end -0.508 -1.199896)
			(stroke
				(width 0.1524)
				(type default)
			)
			(layer "F.SilkS")
		)
		(fp_line
			(start -0.508 -1.199896)
			(end 0 -0.762)
			(stroke
				(width 0.1524)
				(type default)
			)
			(layer "F.SilkS")
		)
		(fp_line
			(start 0.508 -1.199896)
			(end 1.376172 -1.199896)
			(stroke
				(width 0.1524)
				(type default)
			)
			(layer "F.SilkS")
		)
		(fp_line
			(start 1.376172 -1.199896)
			(end 1.376172 1.199896)
			(stroke
				(width 0.1524)
				(type default)
			)
			(layer "F.SilkS")
		)
		(fp_poly
			(pts
				(xy -1.4605 -0.7493) (xy -2.2225 -1.1303) (xy -2.2225 -0.3683)
			)
			(stroke
				(width 0)
				(type default)
			)
			(fill yes)
			(layer "F.SilkS")
		)
		(fp_line
			(start -0.674878 1.100074)
			(end -0.674878 -1.100074)
			(stroke
				(width 0.1)
				(type default)
			)
			(layer "F.Fab")
		)
		(fp_line
			(start 0.674878 1.100074)
			(end -0.674878 1.100074)
			(stroke
				(width 0.1)
				(type default)
			)
			(layer "F.Fab")
		)
		(fp_line
			(start -0.674878 -1.100074)
			(end 0.674878 -1.100074)
			(stroke
				(width 0.1)
				(type default)
			)
			(layer "F.Fab")
		)
		(fp_line
			(start 0.674878 -1.100074)
			(end 0.674878 1.100074)
			(stroke
				(width 0.1)
				(type default)
			)
			(layer "F.Fab")
		)
		(fp_poly
			(pts
				(xy -1.4605 -0.7493) (xy -2.2225 -1.1303) (xy -2.2225 -0.3683)
			)
			(stroke
				(width 0)
				(type default)
			)
			(fill yes)
			(layer "F.Fab")
		)
		(pad "1" smd rect
			(at -0.899922 -0.750062 180)
			(size 0.6096 0.6096)
			(layers "F.Cu" "F.Mask" "F.Paste")
			(net "GND")
		)
		(pad "2" smd rect
			(at -0.899922 0 180)
			(size 0.4064 0.6096)
			(layers "F.Cu" "F.Mask" "F.Paste")
			(net "H_CPU1_MEMHOT_OUT_R")
		)
		(pad "3" smd rect
			(at -0.899922 0.750062 180)
			(size 0.6096 0.6096)
			(layers "F.Cu" "F.Mask" "F.Paste")
			(net "H_CPU1_MEMHOT_OUT")
		)
		(pad "4" smd rect
			(at 0.899922 0.750062 180)
			(size 0.6096 0.6096)
			(layers "F.Cu" "F.Mask" "F.Paste")
			(net "PVNN_TERM_CPU1")
		)
		(pad "5" smd rect
			(at 0.899922 0 180)
			(size 0.4064 0.6096)
			(layers "F.Cu" "F.Mask" "F.Paste")
			(net "H_CPU1_MEMHOT_OUT_VT_R_N")
		)
		(pad "6" smd rect
			(at 0.899922 -0.750062 180)
			(size 0.6096 0.6096)
			(layers "F.Cu" "F.Mask" "F.Paste")
			(net "H_CPU1_MEMHOT_OUT_VT_N")
		)
	)
)
